# S9S_MB_2U (Grand Teton) — schematic netlist excerpt (pin names and nets, part order shuffled) for the footprints in the layout excerpt that follows; sources: Cadence DE-HDL packaged netlist, KiCad conversion of 03242023_DA0F0TMBIJ0_F0T_Motherboard_J_brd_V01_OCP.brd

R28  Q_RES  23.2K 1% CHIP  pkg 0402LF  page 84 : A = PD_CHB_CPU0_DIMM1_SAA ; B = GND
C348  Q_CAP  47UF 4V 20% X6S  pkg C0805  page 79 : A = PVCCIN_CPU1 ; B = GND
R2594  Q_RES  0 5% CHIP  pkg 0402LF  page 274 : A = FM_PVCCINFAON_CPU0_EN ; B = PVCCINFAON_CPU0_EN_R

(kicad_pcb
	(version 20260206)
	(generator "pcbnew")
	(generator_version "10.0")
	(general
		(thickness 1.6)
		(legacy_teardrops no)
	)
	(paper "A4")
	(title_block
		(title "03242023_DA0F0TMBIJ0_F0T_Motherboard_J_brd_V01_OCP.brd")
		(comment 1 "Grand Teton / footprints 5296-5298 of 6105")
	)
	(layers
		(0 "F.Cu" signal "TOP")
		(4 "In1.Cu" signal "GND")
		(6 "In2.Cu" signal "IN1")
		(8 "In3.Cu" signal "GND1")
		(10 "In4.Cu" signal "IN2")
		(12 "In5.Cu" signal "GND2")
		(14 "In6.Cu" signal "IN3")
		(16 "In7.Cu" signal "GND3")
		(18 "In8.Cu" signal "VCC")
		(20 "In9.Cu" signal "VCC1")
		(22 "In10.Cu" signal "GND4")
		(24 "In11.Cu" signal "IN4")
		(26 "In12.Cu" signal "GND5")
		(28 "In13.Cu" signal "IN5")
		(30 "In14.Cu" signal "GND6")
		(32 "In15.Cu" signal "IN6")
		(34 "In16.Cu" signal "GND7")
		(2 "B.Cu" signal "BOTTOM")
		(9 "F.Adhes" user "F.Adhesive")
		(11 "B.Adhes" user "B.Adhesive")
		(13 "F.Paste" user "Package Geometry/Pastemask Top")
		(15 "B.Paste" user "Package Geometry/Pastemask Bottom")
		(5 "F.SilkS" user "Ref Des/Silkscreen Top")
		(7 "B.SilkS" user "Ref Des/Silkscreen Bottom")
		(1 "F.Mask" user "Board Geometry/Soldermask Top")
		(3 "B.Mask" user "Board Geometry/Soldermask Bottom")
		(17 "Dwgs.User" user "User.Drawings")
		(19 "Cmts.User" user "User.Comments")
		(21 "Eco1.User" user "User.Eco1")
		(23 "Eco2.User" user "User.Eco2")
		(25 "Edge.Cuts" user "Board Geometry/Outline")
		(27 "Margin" user)
		(31 "F.CrtYd" user "Package Geometry/Place Bound Top")
		(29 "B.CrtYd" user "Package Geometry/Place Bound Bottom")
		(35 "F.Fab" user "Ref Des/Assembly Top")
		(33 "B.Fab" user "Ref Des/Assembly Bottom")
	)
	(footprint ""
		(layer "B.Cu")
		(at 430.600104 -134.494778)
		(property "Reference" "R2594"
			(at 0 0 0)
			(layer "B.SilkS")
			(hide yes)
			(effects
				(font
					(size 1.27 1.27)
				)
				(justify mirror)
			)
		)
		(property "Value" ""
			(at 0 0 0)
			(layer "B.Fab")
			(effects
				(font
					(size 1.27 1.27)
				)
				(justify mirror)
			)
		)
		(duplicate_pad_numbers_are_jumpers no)
		(fp_line
			(start -0.7874 -0.4064)
			(end -0.7874 0.4064)
			(stroke
				(width 0.1524)
				(type default)
			)
			(layer "B.SilkS")
		)
		(fp_line
			(start -0.7874 0.4064)
			(end 0.7874 0.4064)
			(stroke
				(width 0.1524)
				(type default)
			)
			(layer "B.SilkS")
		)
		(fp_line
			(start 0.7874 -0.4064)
			(end -0.7874 -0.4064)
			(stroke
				(width 0.1524)
				(type default)
			)
			(layer "B.SilkS")
		)
		(fp_line
			(start 0.7874 0.4064)
			(end 0.7874 -0.4064)
			(stroke
				(width 0.1524)
				(type default)
			)
			(layer "B.SilkS")
		)
		(fp_line
			(start -0.67945 -0.3048)
			(end -0.67945 0.3048)
			(stroke
				(width 0.1)
				(type default)
			)
			(layer "B.Fab")
		)
		(fp_line
			(start -0.67945 0.3048)
			(end -0.120396 0.3048)
			(stroke
				(width 0.1)
				(type default)
			)
			(layer "B.Fab")
		)
		(fp_line
			(start -0.12065 -0.3048)
			(end -0.67945 -0.3048)
			(stroke
				(width 0.1)
				(type default)
			)
			(layer "B.Fab")
		)
		(fp_line
			(start -0.12065 -0.2794)
			(end -0.12065 -0.3048)
			(stroke
				(width 0.1)
				(type default)
			)
			(layer "B.Fab")
		)
		(fp_line
			(start -0.120396 0.2794)
			(end 0.12065 0.2794)
			(stroke
				(width 0.1)
				(type default)
			)
			(layer "B.Fab")
		)
		(fp_line
			(start -0.120396 0.3048)
			(end -0.120396 0.2794)
			(stroke
				(width 0.1)
				(type default)
			)
			(layer "B.Fab")
		)
		(fp_line
			(start 0.12065 -0.305054)
			(end 0.12065 -0.2794)
			(stroke
				(width 0.1)
				(type default)
			)
			(layer "B.Fab")
		)
		(fp_line
			(start 0.12065 -0.2794)
			(end -0.12065 -0.2794)
			(stroke
				(width 0.1)
				(type default)
			)
			(layer "B.Fab")
		)
		(fp_line
			(start 0.12065 0.2794)
			(end 0.12065 0.3048)
			(stroke
				(width 0.1)
				(type default)
			)
			(layer "B.Fab")
		)
		(fp_line
			(start 0.12065 0.3048)
			(end 0.67945 0.3048)
			(stroke
				(width 0.1)
				(type default)
			)
			(layer "B.Fab")
		)
		(fp_line
			(start 0.67945 -0.305054)
			(end 0.12065 -0.305054)
			(stroke
				(width 0.1)
				(type default)
			)
			(layer "B.Fab")
		)
		(fp_line
			(start 0.67945 0.3048)
			(end 0.67945 -0.305054)
			(stroke
				(width 0.1)
				(type default)
			)
			(layer "B.Fab")
		)
		(pad "1" smd circle
			(at 0.40005 0 180)
			(size 0 0)
			(layers "B.Cu" "B.Mask" "B.Paste")
			(net "FM_PVCCINFAON_CPU0_EN")
		)
		(pad "2" smd circle
			(at -0.40005 0 180)
			(size 0 0)
			(layers "B.Cu" "B.Mask" "B.Paste")
			(net "PVCCINFAON_CPU0_EN_R")
		)
	)
	(footprint ""
		(layer "B.Cu")
		(at 112.020604 -296.05478)
		(property "Reference" "C348"
			(at 0 0 0)
			(layer "B.SilkS")
			(hide yes)
			(effects
				(font
					(size 1.27 1.27)
				)
				(justify mirror)
			)
		)
		(property "Value" ""
			(at 0 0 0)
			(layer "B.Fab")
			(effects
				(font
					(size 1.27 1.27)
				)
				(justify mirror)
			)
		)
		(duplicate_pad_numbers_are_jumpers no)
		(fp_line
			(start -1.524 -0.762)
			(end -1.524 0.762)
			(stroke
				(width 0.1524)
				(type default)
			)
			(layer "B.SilkS")
		)
		(fp_line
			(start -1.524 0.762)
			(end 1.524 0.762)
			(stroke
				(width 0.1524)
				(type default)
			)
			(layer "B.SilkS")
		)
		(fp_line
			(start 1.524 -0.762)
			(end -1.524 -0.762)
			(stroke
				(width 0.1524)
				(type default)
			)
			(layer "B.SilkS")
		)
		(fp_line
			(start 1.524 0.762)
			(end 1.524 -0.762)
			(stroke
				(width 0.1524)
				(type default)
			)
			(layer "B.SilkS")
		)
		(fp_line
			(start -1.1049 -0.724916)
			(end 1.1049 -0.724916)
			(stroke
				(width 0.1)
				(type default)
			)
			(layer "B.Fab")
		)
		(fp_line
			(start -1.1049 0.724916)
			(end -1.1049 -0.724916)
			(stroke
				(width 0.1)
				(type default)
			)
			(layer "B.Fab")
		)
		(fp_line
			(start 1.1049 -0.724916)
			(end 1.1049 0.724916)
			(stroke
				(width 0.1)
				(type default)
			)
			(layer "B.Fab")
		)
		(fp_line
			(start 1.1049 0.724916)
			(end -1.1049 0.724916)
			(stroke
				(width 0.1)
				(type default)
			)
			(layer "B.Fab")
		)
		(pad "1" smd rect
			(at 0.889 0)
			(size 1.016 1.27)
			(layers "B.Cu" "B.Mask" "B.Paste")
			(net "PVCCIN_CPU1")
		)
		(pad "2" smd rect
			(at -0.889 0)
			(size 1.016 1.27)
			(layers "B.Cu" "B.Mask" "B.Paste")
			(net "GND")
		)
	)
	(footprint ""
		(layer "B.Cu")
		(at 288.175192 -320.004948)
		(property "Reference" "R28"
			(at 0 0 0)
			(layer "B.SilkS")
			(hide yes)
			(effects
				(font
					(size 1.27 1.27)
				)
				(justify mirror)
			)
		)
		(property "Value" ""
			(at 0 0 0)
			(layer "B.Fab")
			(effects
				(font
					(size 1.27 1.27)
				)
				(justify mirror)
			)
		)
		(duplicate_pad_numbers_are_jumpers no)
		(fp_line
			(start -0.7874 -0.4064)
			(end -0.7874 0.4064)
			(stroke
				(width 0.1524)
				(type default)
			)
			(layer "B.SilkS")
		)
		(fp_line
			(start -0.7874 0.4064)
			(end 0.7874 0.4064)
			(stroke
				(width 0.1524)
				(type default)
			)
			(layer "B.SilkS")
		)
		(fp_line
			(start 0.7874 -0.4064)
			(end -0.7874 -0.4064)
			(stroke
				(width 0.1524)
				(type default)
			)
			(layer "B.SilkS")
		)
		(fp_line
			(start 0.7874 0.4064)
			(end 0.7874 -0.4064)
			(stroke
				(width 0.1524)
				(type default)
			)
			(layer "B.SilkS")
		)
		(fp_line
			(start -0.67945 -0.3048)
			(end -0.67945 0.3048)
			(stroke
				(width 0.1)
				(type default)
			)
			(layer "B.Fab")
		)
		(fp_line
			(start -0.67945 0.3048)
			(end -0.120396 0.3048)
			(stroke
				(width 0.1)
				(type default)
			)
			(layer "B.Fab")
		)
		(fp_line
			(start -0.12065 -0.3048)
			(end -0.67945 -0.3048)
			(stroke
				(width 0.1)
				(type default)
			)
			(layer "B.Fab")
		)
		(fp_line
			(start -0.12065 -0.2794)
			(end -0.12065 -0.3048)
			(stroke
				(width 0.1)
				(type default)
			)
			(layer "B.Fab")
		)
		(fp_line
			(start -0.120396 0.2794)
			(end 0.12065 0.2794)
			(stroke
				(width 0.1)
				(type default)
			)
			(layer "B.Fab")
		)
		(fp_line
			(start -0.120396 0.3048)
			(end -0.120396 0.2794)
			(stroke
				(width 0.1)
				(type default)
			)
			(layer "B.Fab")
		)
		(fp_line
			(start 0.12065 -0.305054)
			(end 0.12065 -0.2794)
			(stroke
				(width 0.1)
				(type default)
			)
			(layer "B.Fab")
		)
		(fp_line
			(start 0.12065 -0.2794)
			(end -0.12065 -0.2794)
			(stroke
				(width 0.1)
				(type default)
			)
			(layer "B.Fab")
		)
		(fp_line
			(start 0.12065 0.2794)
			(end 0.12065 0.3048)
			(stroke
				(width 0.1)
				(type default)
			)
			(layer "B.Fab")
		)
		(fp_line
			(start 0.12065 0.3048)
			(end 0.67945 0.3048)
			(stroke
				(width 0.1)
				(type default)
			)
			(layer "B.Fab")
		)
		(fp_line
			(start 0.67945 -0.305054)
			(end 0.12065 -0.305054)
			(stroke
				(width 0.1)
				(type default)
			)
			(layer "B.Fab")
		)
		(fp_line
			(start 0.67945 0.3048)
			(end 0.67945 -0.305054)
			(stroke
				(width 0.1)
				(type default)
			)
			(layer "B.Fab")
		)
		(pad "1" smd circle
			(at 0.40005 0 180)
			(size 0 0)
			(layers "B.Cu" "B.Mask" "B.Paste")
			(net "PD_CHB_CPU0_DIMM1_SAA")
		)
		(pad "2" smd circle
			(at -0.40005 0 180)
			(size 0 0)
			(layers "B.Cu" "B.Mask" "B.Paste")
			(net "GND")
		)
	)
)
